FILE_TYPE = MULTI_PHYS_TABLE;
PART 'SCONN10_C12536004'
{========================================================================================}
:PACK_TYPE | MATERIAL | PART_NUMBER     = EnvComp                  | PART_NUMBER  | JEDEC_TYPE          | CLASS | DESCRIPTION       | HEIGHT     | COMPONENT_TYPE | LEAD_LENGTH | LPID   | SPEED_URL | Status |RPL| AML | Bus_Unit | Days ;
{========================================================================================}
'SMLF'     | 'CONN'   | 'C12536-004'(!) = 'YES;YES;UNK;UNK;ok;VLD' | 'C12536-004' | 'SCONN10_C12536004' | 'IO'  | '2X5 SMT HDR 2MM' | '0.307 IN' | 'SMTCONN'      | ''          | '3197' | 'http://speed.intel.com:8081/speed/module/pdm/item/pdm_item_detail_direct.asp?item_cde=C12536-004&item_rev=01&url_param=unused' | 'Design' | 'NO' | '1' | 'SMO_BOARDS' | '56' 
'SM'       | 'CONN'   | 'C12536-004'(!) = 'YES;YES;UNK;UNK;ok;VLD' | 'C12536-004' | 'SCONN10_C12536004' | 'IO'  | '2X5 SMT HDR 2MM' | '0.307 IN' | 'SMTCONN'      | ''          | '3197' | 'http://speed.intel.com:8081/speed/module/pdm/item/pdm_item_detail_direct.asp?item_cde=C12536-004&item_rev=01&url_param=unused' | 'Design' | 'NO' | '1' | 'SMO_BOARDS' | '56' 
'SMLF'     | 'EMPTY'  | 'C12536-004'(!) = 'YES;YES;UNK;UNK;ok;VLD' | 'C12536-004' | 'SCONN10_C12536004' | 'IO'  | '2X5 SMT HDR 2MM' | '0.307 IN' | 'SMTCONN'      | ''          | '3197' | 'http://speed.intel.com:8081/speed/module/pdm/item/pdm_item_detail_direct.asp?item_cde=C12536-004&item_rev=01&url_param=unused' | 'Design' | 'NO' | '1' | 'SMO_BOARDS' | '56' 
'SM'       | 'EMPTY'  | 'C12536-004'(!) = 'YES;YES;UNK;UNK;ok;VLD' | 'C12536-004' | 'SCONN10_C12536004' | 'IO'  | '2X5 SMT HDR 2MM' | '0.307 IN' | 'SMTCONN'      | ''          | '3197' | 'http://speed.intel.com:8081/speed/module/pdm/item/pdm_item_detail_direct.asp?item_cde=C12536-004&item_rev=01&url_param=unused' | 'Design' | 'NO' | '1' | 'SMO_BOARDS' | '56' 
END_PART
END.
